(kicad_pcb
	(version 20260206)
	(generator "pcbnew")
	(generator_version "10.0")
	(general
		(thickness 1.6)
		(legacy_teardrops no)
	)
	(paper "A4")
	(title_block
		(title "01162023_DA0F0TEBIF0_F0T_Expander_BD_F_brd_V02_OCP.brd")
		(comment 1 "Grand Teton / footprints 7302-7308 of 9728")
	)
	(layers
		(0 "F.Cu" signal "TOP")
		(4 "In1.Cu" signal "GND")
		(6 "In2.Cu" signal "VCC")
		(8 "In3.Cu" signal "VCC1")
		(10 "In4.Cu" signal "GND1")
		(12 "In5.Cu" signal "IN1")
		(14 "In6.Cu" signal "GND2")
		(16 "In7.Cu" signal "IN2")
		(18 "In8.Cu" signal "GND3")
		(20 "In9.Cu" signal "IN3")
		(22 "In10.Cu" signal "GND4")
		(24 "In11.Cu" signal "IN4")
		(26 "In12.Cu" signal "GND5")
		(28 "In13.Cu" signal "IN5")
		(30 "In14.Cu" signal "GND6")
		(32 "In15.Cu" signal "IN6")
		(34 "In16.Cu" signal "GND7")
		(2 "B.Cu" signal "BOTTOM")
		(9 "F.Adhes" user "F.Adhesive")
		(11 "B.Adhes" user "B.Adhesive")
		(13 "F.Paste" user "Package Geometry/Pastemask Top")
		(15 "B.Paste" user "Package Geometry/Pastemask Bottom")
		(5 "F.SilkS" user "Ref Des/Silkscreen Top")
		(7 "B.SilkS" user "Ref Des/Silkscreen Bottom")
		(1 "F.Mask" user "Board Geometry/Soldermask Top")
		(3 "B.Mask" user "Board Geometry/Soldermask Bottom")
		(17 "Dwgs.User" user "User.Drawings")
		(19 "Cmts.User" user "User.Comments")
		(21 "Eco1.User" user "User.Eco1")
		(23 "Eco2.User" user "User.Eco2")
		(25 "Edge.Cuts" user "Board Geometry/Outline")
		(27 "Margin" user)
		(31 "F.CrtYd" user "Package Geometry/Place Bound Top")
		(29 "B.CrtYd" user "Package Geometry/Place Bound Bottom")
		(35 "F.Fab" user "Ref Des/Assembly Top")
		(33 "B.Fab" user "Ref Des/Assembly Bottom")
	)
	(footprint ""
		(layer "B.Cu")
		(at 265.66368 -89.142316)
		(property "Reference" "L10"
			(at 0 0 0)
			(layer "B.SilkS")
			(hide yes)
			(effects
				(font
					(size 1.27 1.27)
				)
				(justify mirror)
			)
		)
		(property "Value" ""
			(at 0 0 0)
			(layer "B.Fab")
			(effects
				(font
					(size 1.27 1.27)
				)
				(justify mirror)
			)
		)
		(duplicate_pad_numbers_are_jumpers no)
		(fp_line
			(start -1.63576 -0.8128)
			(end -1.63576 0.8128)
			(stroke
				(width 0.1524)
				(type default)
			)
			(layer "B.SilkS")
		)
		(fp_line
			(start -1.63576 0.8128)
			(end 1.63576 0.8128)
			(stroke
				(width 0.1524)
				(type default)
			)
			(layer "B.SilkS")
		)
		(fp_line
			(start 1.63576 -0.8128)
			(end -1.63576 -0.8128)
			(stroke
				(width 0.1524)
				(type default)
			)
			(layer "B.SilkS")
		)
		(fp_line
			(start 1.63576 -0.8128)
			(end 1.63576 0.8128)
			(stroke
				(width 0.1524)
				(type default)
			)
			(layer "B.SilkS")
		)
		(fp_line
			(start -1.560576 -0.738632)
			(end 1.56083 -0.738632)
			(stroke
				(width 0.1)
				(type default)
			)
			(layer "B.Fab")
		)
		(fp_line
			(start -1.560576 0.7366)
			(end -1.560576 -0.738632)
			(stroke
				(width 0.1)
				(type default)
			)
			(layer "B.Fab")
		)
		(fp_line
			(start -1.524 0.7366)
			(end -1.560576 0.7366)
			(stroke
				(width 0.1)
				(type default)
			)
			(layer "B.Fab")
		)
		(fp_line
			(start 1.524 0.7366)
			(end -1.524 0.7366)
			(stroke
				(width 0.1)
				(type default)
			)
			(layer "B.Fab")
		)
		(fp_line
			(start 1.56083 -0.738632)
			(end 1.56083 0.7366)
			(stroke
				(width 0.1)
				(type default)
			)
			(layer "B.Fab")
		)
		(fp_line
			(start 1.56083 0.7366)
			(end 1.524 0.7366)
			(stroke
				(width 0.1)
				(type default)
			)
			(layer "B.Fab")
		)
		(pad "1" smd rect
			(at 0.94996 0)
			(size 1.1176 1.3716)
			(layers "B.Cu" "B.Mask" "B.Paste")
			(net "P3V3")
		)
		(pad "2" smd rect
			(at -0.94996 0)
			(size 1.1176 1.3716)
			(layers "B.Cu" "B.Mask" "B.Paste")
			(net "P3V3_CLK_GEN_VDDMXCK_CK440")
		)
	)
	(footprint ""
		(layer "B.Cu")
		(at 13.513054 -288.972752 180)
		(property "Reference" "PC988"
			(at 0 0 0)
			(layer "B.SilkS")
			(hide yes)
			(effects
				(font
					(size 1.27 1.27)
				)
				(justify mirror)
			)
		)
		(property "Value" ""
			(at 0 0 0)
			(layer "B.Fab")
			(effects
				(font
					(size 1.27 1.27)
				)
				(justify mirror)
			)
		)
		(duplicate_pad_numbers_are_jumpers no)
		(fp_line
			(start 1.524 0.762)
			(end 1.524 -0.762)
			(stroke
				(width 0.1524)
				(type default)
			)
			(layer "B.SilkS")
		)
		(fp_line
			(start 1.524 -0.762)
			(end -1.524 -0.762)
			(stroke
				(width 0.1524)
				(type default)
			)
			(layer "B.SilkS")
		)
		(fp_line
			(start -1.524 0.762)
			(end 1.524 0.762)
			(stroke
				(width 0.1524)
				(type default)
			)
			(layer "B.SilkS")
		)
		(fp_line
			(start -1.524 -0.762)
			(end -1.524 0.762)
			(stroke
				(width 0.1524)
				(type default)
			)
			(layer "B.SilkS")
		)
		(fp_line
			(start 1.1049 0.724916)
			(end -1.1049 0.724916)
			(stroke
				(width 0.1)
				(type default)
			)
			(layer "B.Fab")
		)
		(fp_line
			(start 1.1049 -0.724916)
			(end 1.1049 0.724916)
			(stroke
				(width 0.1)
				(type default)
			)
			(layer "B.Fab")
		)
		(fp_line
			(start -1.1049 0.724916)
			(end -1.1049 -0.724916)
			(stroke
				(width 0.1)
				(type default)
			)
			(layer "B.Fab")
		)
		(fp_line
			(start -1.1049 -0.724916)
			(end 1.1049 -0.724916)
			(stroke
				(width 0.1)
				(type default)
			)
			(layer "B.Fab")
		)
		(pad "1" smd rect
			(at 0.889 0 180)
			(size 1.016 1.27)
			(layers "B.Cu" "B.Mask" "B.Paste")
			(net "P1V25_PEX0_R")
		)
		(pad "2" smd rect
			(at -0.889 0 180)
			(size 1.016 1.27)
			(layers "B.Cu" "B.Mask" "B.Paste")
			(net "GND")
		)
	)
	(footprint ""
		(layer "B.Cu")
		(at 54.864762 -140.931138 180)
		(property "Reference" "U8"
			(at -0.21971 1.912874 0)
			(unlocked yes)
			(layer "B.SilkS")
			(effects
				(font
					(size 0.7874 0.5842)
					(thickness 0.1524)
				)
				(justify mirror)
			)
		)
		(property "Value" ""
			(at 0 0 0)
			(layer "B.Fab")
			(effects
				(font
					(size 1.27 1.27)
				)
				(justify mirror)
			)
		)
		(duplicate_pad_numbers_are_jumpers no)
		(fp_line
			(start 1.3462 1.1938)
			(end -1.3462 1.1938)
			(stroke
				(width 0.1524)
				(type default)
			)
			(layer "B.SilkS")
		)
		(fp_line
			(start 1.3462 -1.1938)
			(end 1.3462 1.1684)
			(stroke
				(width 0.1524)
				(type default)
			)
			(layer "B.SilkS")
		)
		(fp_line
			(start -1.3462 1.1938)
			(end -1.3462 -1.1938)
			(stroke
				(width 0.1524)
				(type default)
			)
			(layer "B.SilkS")
		)
		(fp_line
			(start -1.3462 -1.1938)
			(end 1.3462 -1.1938)
			(stroke
				(width 0.1524)
				(type default)
			)
			(layer "B.SilkS")
		)
		(fp_poly
			(pts
				(xy 1.447038 -0.760476) (xy 2.052066 -0.457962) (xy 2.052066 -1.06299)
			)
			(stroke
				(width 0)
				(type default)
			)
			(fill yes)
			(layer "B.SilkS")
		)
		(fp_line
			(start 0.674878 1.124966)
			(end -0.674878 1.124966)
			(stroke
				(width 0.1)
				(type default)
			)
			(layer "B.Fab")
		)
		(fp_line
			(start 0.674878 -1.124966)
			(end 0.674878 1.124966)
			(stroke
				(width 0.1)
				(type default)
			)
			(layer "B.Fab")
		)
		(fp_line
			(start -0.674878 1.124966)
			(end -0.674878 -1.124966)
			(stroke
				(width 0.1)
				(type default)
			)
			(layer "B.Fab")
		)
		(fp_line
			(start -0.674878 -1.124966)
			(end 0.674878 -1.124966)
			(stroke
				(width 0.1)
				(type default)
			)
			(layer "B.Fab")
		)
		(fp_poly
			(pts
				(xy 1.447038 -0.760476) (xy 2.052066 -0.457962) (xy 2.052066 -1.06299)
			)
			(stroke
				(width 0)
				(type default)
			)
			(fill yes)
			(layer "B.Fab")
		)
		(pad "1" smd rect
			(at 0.899922 -0.750062)
			(size 0.6096 0.6096)
			(layers "B.Cu" "B.Mask" "B.Paste")
			(net "NIC0_AUX_PWR_EN_R")
		)
		(pad "2" smd rect
			(at 0.899922 0 270)
			(size 0.4064 0.6096)
			(layers "B.Cu" "B.Mask" "B.Paste")
			(net "RST_SMB_NIC0_MUX_N")
		)
		(pad "3" smd rect
			(at 0.899922 0.750062)
			(size 0.6096 0.6096)
			(layers "B.Cu" "B.Mask" "B.Paste")
			(net "GND")
		)
		(pad "4" smd rect
			(at -0.899922 0.750062)
			(size 0.6096 0.6096)
			(layers "B.Cu" "B.Mask" "B.Paste")
			(net "RST_SMB_NIC0_MUX_ISO_N")
		)
		(pad "5" smd rect
			(at -0.899922 -0.750062)
			(size 0.6096 0.6096)
			(layers "B.Cu" "B.Mask" "B.Paste")
			(net "P3V3_AUX")
		)
	)
	(footprint ""
		(layer "B.Cu")
		(at 386.316982 -232.858564 90)
		(property "Reference" "C2576"
			(at 0 0 90)
			(layer "B.SilkS")
			(hide yes)
			(effects
				(font
					(size 1.27 1.27)
				)
				(justify mirror)
			)
		)
		(property "Value" ""
			(at 0 0 90)
			(layer "B.Fab")
			(effects
				(font
					(size 1.27 1.27)
				)
				(justify mirror)
			)
		)
		(duplicate_pad_numbers_are_jumpers no)
		(fp_line
			(start 0.7874 -0.4064)
			(end -0.7874 -0.4064)
			(stroke
				(width 0.1524)
				(type default)
			)
			(layer "B.SilkS")
		)
		(fp_line
			(start -0.7874 -0.4064)
			(end -0.7874 0.4064)
			(stroke
				(width 0.1524)
				(type default)
			)
			(layer "B.SilkS")
		)
		(fp_line
			(start 0.7874 0.4064)
			(end 0.7874 -0.4064)
			(stroke
				(width 0.1524)
				(type default)
			)
			(layer "B.SilkS")
		)
		(fp_line
			(start -0.7874 0.4064)
			(end 0.7874 0.4064)
			(stroke
				(width 0.1524)
				(type default)
			)
			(layer "B.SilkS")
		)
		(fp_line
			(start 0.67945 -0.305054)
			(end 0.12065 -0.305054)
			(stroke
				(width 0.1)
				(type default)
			)
			(layer "B.Fab")
		)
		(fp_line
			(start 0.12065 -0.305054)
			(end 0.12065 -0.2794)
			(stroke
				(width 0.1)
				(type default)
			)
			(layer "B.Fab")
		)
		(fp_line
			(start -0.12065 -0.3048)
			(end -0.67945 -0.3048)
			(stroke
				(width 0.1)
				(type default)
			)
			(layer "B.Fab")
		)
		(fp_line
			(start -0.67945 -0.3048)
			(end -0.67945 0.3048)
			(stroke
				(width 0.1)
				(type default)
			)
			(layer "B.Fab")
		)
		(fp_line
			(start 0.12065 -0.2794)
			(end -0.12065 -0.2794)
			(stroke
				(width 0.1)
				(type default)
			)
			(layer "B.Fab")
		)
		(fp_line
			(start -0.12065 -0.2794)
			(end -0.12065 -0.3048)
			(stroke
				(width 0.1)
				(type default)
			)
			(layer "B.Fab")
		)
		(fp_line
			(start 0.12065 0.2794)
			(end 0.12065 0.3048)
			(stroke
				(width 0.1)
				(type default)
			)
			(layer "B.Fab")
		)
		(fp_line
			(start -0.120396 0.2794)
			(end 0.12065 0.2794)
			(stroke
				(width 0.1)
				(type default)
			)
			(layer "B.Fab")
		)
		(fp_line
			(start 0.67945 0.3048)
			(end 0.67945 -0.305054)
			(stroke
				(width 0.1)
				(type default)
			)
			(layer "B.Fab")
		)
		(fp_line
			(start 0.12065 0.3048)
			(end 0.67945 0.3048)
			(stroke
				(width 0.1)
				(type default)
			)
			(layer "B.Fab")
		)
		(fp_line
			(start -0.120396 0.3048)
			(end -0.120396 0.2794)
			(stroke
				(width 0.1)
				(type default)
			)
			(layer "B.Fab")
		)
		(fp_line
			(start -0.67945 0.3048)
			(end -0.120396 0.3048)
			(stroke
				(width 0.1)
				(type default)
			)
			(layer "B.Fab")
		)
		(pad "1" smd circle
			(at 0.40005 0 270)
			(size 0 0)
			(layers "B.Cu" "B.Mask" "B.Paste")
			(net "P1V8_SDB_VCORE")
		)
		(pad "2" smd circle
			(at -0.40005 0 270)
			(size 0 0)
			(layers "B.Cu" "B.Mask" "B.Paste")
			(net "GND")
		)
	)
	(footprint ""
		(layer "B.Cu")
		(at 366.492536 -327.3552)
		(property "Reference" "PJ25"
			(at 0 0 0)
			(layer "B.SilkS")
			(hide yes)
			(effects
				(font
					(size 1.27 1.27)
				)
				(justify mirror)
			)
		)
		(property "Value" ""
			(at 0 0 0)
			(layer "B.Fab")
			(effects
				(font
					(size 1.27 1.27)
				)
				(justify mirror)
			)
		)
		(duplicate_pad_numbers_are_jumpers no)
		(pad "1" smd circle
			(at 0.40005 0 90)
			(size 0 0)
			(layers "B.Cu" "B.Mask" "B.Paste")
			(net "VSENSE_P0V8_PEX3_SKT_VRTN")
		)
		(pad "2" smd rect
			(at -0.40005 0)
			(size 0.4572 0.508)
			(layers "B.Cu" "B.Mask" "B.Paste")
			(net "SH_P0V8_PEX3_RGND3")
		)
		(zone
			(layer "B.Cu")
			(hatch none 0.5)
			(connect_pads
				(clearance 0)
			)
			(min_thickness 0.25)
			(keepout
				(tracks allowed)
				(vias not_allowed)
				(pads allowed)
				(copperpour not_allowed)
				(footprints allowed)
			)
			(placement
				(enabled no)
				(sheetname "")
			)
			(fill
				(thermal_gap 0.5)
				(thermal_bridge_width 0.5)
				(island_removal_mode 0)
			)
			(polygon
				(pts
					(xy 365.806736 -327.0504) (xy 365.806736 -327.66) (xy 367.178336 -327.66) (xy 367.178336 -327.0504)
				)
			)
		)
	)
	(footprint ""
		(layer "B.Cu")
		(at 396.120366 -302.028606)
		(property "Reference" "C3510"
			(at 0 0 0)
			(layer "B.SilkS")
			(hide yes)
			(effects
				(font
					(size 1.27 1.27)
				)
				(justify mirror)
			)
		)
		(property "Value" ""
			(at 0 0 0)
			(layer "B.Fab")
			(effects
				(font
					(size 1.27 1.27)
				)
				(justify mirror)
			)
		)
		(duplicate_pad_numbers_are_jumpers no)
		(fp_line
			(start -1.2954 -0.5842)
			(end -1.2954 0.5842)
			(stroke
				(width 0.1524)
				(type default)
			)
			(layer "B.SilkS")
		)
		(fp_line
			(start -1.2954 0.5842)
			(end 1.2954 0.5842)
			(stroke
				(width 0.1524)
				(type default)
			)
			(layer "B.SilkS")
		)
		(fp_line
			(start 1.2954 -0.5842)
			(end -1.2954 -0.5842)
			(stroke
				(width 0.1524)
				(type default)
			)
			(layer "B.SilkS")
		)
		(fp_line
			(start 1.2954 0.5842)
			(end 1.2954 -0.5842)
			(stroke
				(width 0.1524)
				(type default)
			)
			(layer "B.SilkS")
		)
		(fp_line
			(start -1.1938 -0.4064)
			(end -1.1938 0.4064)
			(stroke
				(width 0.1)
				(type default)
			)
			(layer "B.Fab")
		)
		(fp_line
			(start -1.1938 0.4064)
			(end -0.8636 0.4064)
			(stroke
				(width 0.1)
				(type default)
			)
			(layer "B.Fab")
		)
		(fp_line
			(start -0.8636 -0.4572)
			(end -0.8636 -0.4064)
			(stroke
				(width 0.1)
				(type default)
			)
			(layer "B.Fab")
		)
		(fp_line
			(start -0.8636 -0.4064)
			(end -1.1938 -0.4064)
			(stroke
				(width 0.1)
				(type default)
			)
			(layer "B.Fab")
		)
		(fp_line
			(start -0.8636 0.4064)
			(end -0.8636 0.4572)
			(stroke
				(width 0.1)
				(type default)
			)
			(layer "B.Fab")
		)
		(fp_line
			(start -0.8636 0.4572)
			(end 0.8636 0.4572)
			(stroke
				(width 0.1)
				(type default)
			)
			(layer "B.Fab")
		)
		(fp_line
			(start 0.8636 -0.4572)
			(end -0.8636 -0.4572)
			(stroke
				(width 0.1)
				(type default)
			)
			(layer "B.Fab")
		)
		(fp_line
			(start 0.8636 -0.4064)
			(end 0.8636 -0.4572)
			(stroke
				(width 0.1)
				(type default)
			)
			(layer "B.Fab")
		)
		(fp_line
			(start 0.8636 0.4064)
			(end 1.1938 0.4064)
			(stroke
				(width 0.1)
				(type default)
			)
			(layer "B.Fab")
		)
		(fp_line
			(start 0.8636 0.4572)
			(end 0.8636 0.4064)
			(stroke
				(width 0.1)
				(type default)
			)
			(layer "B.Fab")
		)
		(fp_line
			(start 1.1938 -0.4064)
			(end 0.8636 -0.4064)
			(stroke
				(width 0.1)
				(type default)
			)
			(layer "B.Fab")
		)
		(fp_line
			(start 1.1938 0.4064)
			(end 1.1938 -0.4064)
			(stroke
				(width 0.1)
				(type default)
			)
			(layer "B.Fab")
		)
		(pad "1" smd rect
			(at 0.7366 0 270)
			(size 0.7112 0.8128)
			(layers "B.Cu" "B.Mask" "B.Paste")
			(net "P1V8_VDDA_PEX3")
		)
		(pad "2" smd rect
			(at -0.7366 0 270)
			(size 0.7112 0.8128)
			(layers "B.Cu" "B.Mask" "B.Paste")
			(net "GND")
		)
	)
	(footprint ""
		(layer "B.Cu")
		(at 59.160664 -305.557936 -90)
		(property "Reference" "C2945"
			(at 0 0 90)
			(layer "B.SilkS")
			(hide yes)
			(effects
				(font
					(size 1.27 1.27)
				)
				(justify mirror)
			)
		)
		(property "Value" ""
			(at 0 0 90)
			(layer "B.Fab")
			(effects
				(font
					(size 1.27 1.27)
				)
				(justify mirror)
			)
		)
		(duplicate_pad_numbers_are_jumpers no)
		(fp_line
			(start -1.2954 0.5842)
			(end 1.2954 0.5842)
			(stroke
				(width 0.1524)
				(type default)
			)
			(layer "B.SilkS")
		)
		(fp_line
			(start 1.2954 0.5842)
			(end 1.2954 -0.5842)
			(stroke
				(width 0.1524)
				(type default)
			)
			(layer "B.SilkS")
		)
		(fp_line
			(start -1.2954 -0.5842)
			(end -1.2954 0.5842)
			(stroke
				(width 0.1524)
				(type default)
			)
			(layer "B.SilkS")
		)
		(fp_line
			(start 1.2954 -0.5842)
			(end -1.2954 -0.5842)
			(stroke
				(width 0.1524)
				(type default)
			)
			(layer "B.SilkS")
		)
		(fp_line
			(start -0.8636 0.4572)
			(end 0.8636 0.4572)
			(stroke
				(width 0.1)
				(type default)
			)
			(layer "B.Fab")
		)
		(fp_line
			(start 0.8636 0.4572)
			(end 0.8636 0.4064)
			(stroke
				(width 0.1)
				(type default)
			)
			(layer "B.Fab")
		)
		(fp_line
			(start -1.1938 0.4064)
			(end -0.8636 0.4064)
			(stroke
				(width 0.1)
				(type default)
			)
			(layer "B.Fab")
		)
		(fp_line
			(start -0.8636 0.4064)
			(end -0.8636 0.4572)
			(stroke
				(width 0.1)
				(type default)
			)
			(layer "B.Fab")
		)
		(fp_line
			(start 0.8636 0.4064)
			(end 1.1938 0.4064)
			(stroke
				(width 0.1)
				(type default)
			)
			(layer "B.Fab")
		)
		(fp_line
			(start 1.1938 0.4064)
			(end 1.1938 -0.4064)
			(stroke
				(width 0.1)
				(type default)
			)
			(layer "B.Fab")
		)
		(fp_line
			(start -1.1938 -0.4064)
			(end -1.1938 0.4064)
			(stroke
				(width 0.1)
				(type default)
			)
			(layer "B.Fab")
		)
		(fp_line
			(start -0.8636 -0.4064)
			(end -1.1938 -0.4064)
			(stroke
				(width 0.1)
				(type default)
			)
			(layer "B.Fab")
		)
		(fp_line
			(start 0.8636 -0.4064)
			(end 0.8636 -0.4572)
			(stroke
				(width 0.1)
				(type default)
			)
			(layer "B.Fab")
		)
		(fp_line
			(start 1.1938 -0.4064)
			(end 0.8636 -0.4064)
			(stroke
				(width 0.1)
				(type default)
			)
			(layer "B.Fab")
		)
		(fp_line
			(start -0.8636 -0.4572)
			(end -0.8636 -0.4064)
			(stroke
				(width 0.1)
				(type default)
			)
			(layer "B.Fab")
		)
		(fp_line
			(start 0.8636 -0.4572)
			(end -0.8636 -0.4572)
			(stroke
				(width 0.1)
				(type default)
			)
			(layer "B.Fab")
		)
		(pad "1" smd rect
			(at 0.7366 0 180)
			(size 0.7112 0.8128)
			(layers "B.Cu" "B.Mask" "B.Paste")
			(net "P1V25_SERDES_VDDPLL_PEX0")
		)
		(pad "2" smd rect
			(at -0.7366 0 180)
			(size 0.7112 0.8128)
			(layers "B.Cu" "B.Mask" "B.Paste")
			(net "GND")
		)
	)
)
